(kicad_pcb
	(version 20260206)
	(generator "pcbnew")
	(generator_version "10.0")
	(general
		(thickness 1.6)
		(legacy_teardrops no)
	)
	(paper "A4")
	(title_block
		(title "Wiwynn_Tioga_Pass_MB.brd")
		(comment 1 "Tioga Pass / footprints 2989-2995 of 4770")
	)
	(layers
		(0 "F.Cu" signal "TOP")
		(4 "In1.Cu" signal "L2GND")
		(6 "In2.Cu" signal "L3")
		(8 "In3.Cu" signal "L4GND")
		(10 "In4.Cu" signal "L5")
		(12 "In5.Cu" signal "L6GND")
		(14 "In6.Cu" signal "L7VCC")
		(16 "In7.Cu" signal "L8VCC")
		(18 "In8.Cu" signal "L9GND")
		(20 "In9.Cu" signal "L10")
		(22 "In10.Cu" signal "L11GND")
		(24 "In11.Cu" signal "L12")
		(26 "In12.Cu" signal "L13GND")
		(2 "B.Cu" signal "BOTTOM")
		(9 "F.Adhes" user "F.Adhesive")
		(11 "B.Adhes" user "B.Adhesive")
		(13 "F.Paste" user "Package Geometry/Pastemask Top")
		(15 "B.Paste" user "Package Geometry/Pastemask Bottom")
		(5 "F.SilkS" user "Ref Des/Silkscreen Top")
		(7 "B.SilkS" user "Ref Des/Silkscreen Bottom")
		(1 "F.Mask" user "Board Geometry/Soldermask Top")
		(3 "B.Mask" user "Board Geometry/Soldermask Bottom")
		(17 "Dwgs.User" user "User.Drawings")
		(19 "Cmts.User" user "User.Comments")
		(21 "Eco1.User" user "User.Eco1")
		(23 "Eco2.User" user "User.Eco2")
		(25 "Edge.Cuts" user "Board Geometry/Outline")
		(27 "Margin" user)
		(31 "F.CrtYd" user "Package Geometry/Place Bound Top")
		(29 "B.CrtYd" user "Package Geometry/Place Bound Bottom")
		(35 "F.Fab" user "Ref Des/Assembly Top")
		(33 "B.Fab" user "Ref Des/Assembly Bottom")
	)
	(footprint ""
		(layer "B.Cu")
		(at 369.864386 -47.827184 -90)
		(property "Reference" "R2T50"
			(at 0 0 90)
			(layer "B.SilkS")
			(hide yes)
			(effects
				(font
					(size 1.27 1.27)
				)
				(justify mirror)
			)
		)
		(property "Value" ""
			(at 0 0 90)
			(layer "B.Fab")
			(effects
				(font
					(size 1.27 1.27)
				)
				(justify mirror)
			)
		)
		(duplicate_pad_numbers_are_jumpers no)
		(fp_poly
			(pts
				(xy 0.2794 -0.1016) (xy -0.2794 -0.1016) (xy -0.2794 0.9906) (xy 0.2794 0.9906)
			)
			(stroke
				(width 0)
				(type default)
			)
			(fill no)
			(layer "B.CrtYd")
		)
		(fp_line
			(start -0.2794 0.9906)
			(end -0.2794 -0.1016)
			(stroke
				(width 0.1)
				(type default)
			)
			(layer "B.Fab")
		)
		(fp_line
			(start 0.2794 0.9906)
			(end -0.2794 0.9906)
			(stroke
				(width 0.1)
				(type default)
			)
			(layer "B.Fab")
		)
		(fp_line
			(start -0.2794 -0.1016)
			(end 0.2794 -0.1016)
			(stroke
				(width 0.1)
				(type default)
			)
			(layer "B.Fab")
		)
		(fp_line
			(start 0.2794 -0.1016)
			(end 0.2794 0.9906)
			(stroke
				(width 0.1)
				(type default)
			)
			(layer "B.Fab")
		)
		(pad "1" smd rect
			(at 0 0 90)
			(size 0.508 0.508)
			(layers "B.Cu" "B.Mask" "B.Paste")
			(net "PD_GTL2104_4_DIR")
		)
		(pad "2" smd rect
			(at 0 0.889 90)
			(size 0.508 0.508)
			(layers "B.Cu" "B.Mask" "B.Paste")
			(net "GND")
		)
		(zone
			(layer "B.Cu")
			(hatch none 0.5)
			(connect_pads
				(clearance 0)
			)
			(min_thickness 0.25)
			(keepout
				(tracks not_allowed)
				(vias allowed)
				(pads allowed)
				(copperpour not_allowed)
				(footprints allowed)
			)
			(placement
				(enabled no)
				(sheetname "")
			)
			(fill
				(thermal_gap 0.5)
				(thermal_bridge_width 0.5)
				(island_removal_mode 0)
			)
			(polygon
				(pts
					(xy 369.229386 -47.573184) (xy 369.229386 -48.081184) (xy 369.610386 -48.081184) (xy 369.610386 -47.573184)
				)
			)
		)
		(zone
			(layer "B.Cu")
			(hatch none 0.5)
			(connect_pads
				(clearance 0)
			)
			(min_thickness 0.25)
			(keepout
				(tracks allowed)
				(vias not_allowed)
				(pads allowed)
				(copperpour not_allowed)
				(footprints allowed)
			)
			(placement
				(enabled no)
				(sheetname "")
			)
			(fill
				(thermal_gap 0.5)
				(thermal_bridge_width 0.5)
				(island_removal_mode 0)
			)
			(polygon
				(pts
					(xy 369.610386 -47.573184) (xy 369.610386 -48.081184) (xy 369.229386 -48.081184) (xy 369.229386 -47.573184)
				)
			)
		)
	)
	(footprint ""
		(layer "B.Cu")
		(at 153.543 -17.78 -90)
		(property "Reference" "C7T3"
			(at 0 0 90)
			(layer "B.SilkS")
			(hide yes)
			(effects
				(font
					(size 1.27 1.27)
				)
				(justify mirror)
			)
		)
		(property "Value" ""
			(at 0 0 90)
			(layer "B.Fab")
			(effects
				(font
					(size 1.27 1.27)
				)
				(justify mirror)
			)
		)
		(duplicate_pad_numbers_are_jumpers no)
		(fp_poly
			(pts
				(xy 0.4953 -0.2032) (xy -0.4953 -0.2032) (xy -0.4953 1.6002) (xy 0.4953 1.6002)
			)
			(stroke
				(width 0)
				(type default)
			)
			(fill no)
			(layer "B.CrtYd")
		)
		(fp_line
			(start -0.4953 1.6002)
			(end 0.4953 1.6002)
			(stroke
				(width 0.1)
				(type default)
			)
			(layer "B.Fab")
		)
		(fp_line
			(start 0.4953 1.6002)
			(end 0.4953 -0.2032)
			(stroke
				(width 0.1)
				(type default)
			)
			(layer "B.Fab")
		)
		(fp_line
			(start -0.4953 -0.2032)
			(end -0.4953 1.6002)
			(stroke
				(width 0.1)
				(type default)
			)
			(layer "B.Fab")
		)
		(fp_line
			(start 0.4953 -0.2032)
			(end -0.4953 -0.2032)
			(stroke
				(width 0.1)
				(type default)
			)
			(layer "B.Fab")
		)
		(pad "1" smd rect
			(at 0 0 90)
			(size 0.762 0.889)
			(layers "B.Cu" "B.Mask" "B.Paste")
			(net "PVPP_GHJ")
		)
		(pad "2" smd rect
			(at 0 1.397 90)
			(size 0.762 0.889)
			(layers "B.Cu" "B.Mask" "B.Paste")
			(net "GND")
		)
		(zone
			(layer "B.Cu")
			(hatch none 0.5)
			(connect_pads
				(clearance 0)
			)
			(min_thickness 0.25)
			(keepout
				(tracks not_allowed)
				(vias allowed)
				(pads allowed)
				(copperpour not_allowed)
				(footprints allowed)
			)
			(placement
				(enabled no)
				(sheetname "")
			)
			(fill
				(thermal_gap 0.5)
				(thermal_bridge_width 0.5)
				(island_removal_mode 0)
			)
			(polygon
				(pts
					(xy 153.0985 -17.399) (xy 153.0985 -18.161) (xy 152.5905 -18.161) (xy 152.5905 -17.399)
				)
			)
		)
	)
	(footprint ""
		(layer "B.Cu")
		(at 171.069 -74.93)
		(property "Reference" "R6P21"
			(at 0 0 0)
			(layer "B.SilkS")
			(hide yes)
			(effects
				(font
					(size 1.27 1.27)
				)
				(justify mirror)
			)
		)
		(property "Value" ""
			(at 0 0 0)
			(layer "B.Fab")
			(effects
				(font
					(size 1.27 1.27)
				)
				(justify mirror)
			)
		)
		(duplicate_pad_numbers_are_jumpers no)
		(fp_poly
			(pts
				(xy 0.2794 -0.1016) (xy -0.2794 -0.1016) (xy -0.2794 0.9906) (xy 0.2794 0.9906)
			)
			(stroke
				(width 0)
				(type default)
			)
			(fill no)
			(layer "B.CrtYd")
		)
		(fp_line
			(start -0.2794 -0.1016)
			(end 0.2794 -0.1016)
			(stroke
				(width 0.1)
				(type default)
			)
			(layer "B.Fab")
		)
		(fp_line
			(start -0.2794 0.9906)
			(end -0.2794 -0.1016)
			(stroke
				(width 0.1)
				(type default)
			)
			(layer "B.Fab")
		)
		(fp_line
			(start 0.2794 -0.1016)
			(end 0.2794 0.9906)
			(stroke
				(width 0.1)
				(type default)
			)
			(layer "B.Fab")
		)
		(fp_line
			(start 0.2794 0.9906)
			(end -0.2794 0.9906)
			(stroke
				(width 0.1)
				(type default)
			)
			(layer "B.Fab")
		)
		(pad "1" smd rect
			(at 0 0 180)
			(size 0.508 0.508)
			(layers "B.Cu" "B.Mask" "B.Paste")
			(net "FM_DB1200_SMB_SA0")
		)
		(pad "2" smd rect
			(at 0 0.889 180)
			(size 0.508 0.508)
			(layers "B.Cu" "B.Mask" "B.Paste")
			(net "GND")
		)
		(zone
			(layer "B.Cu")
			(hatch none 0.5)
			(connect_pads
				(clearance 0)
			)
			(min_thickness 0.25)
			(keepout
				(tracks allowed)
				(vias not_allowed)
				(pads allowed)
				(copperpour not_allowed)
				(footprints allowed)
			)
			(placement
				(enabled no)
				(sheetname "")
			)
			(fill
				(thermal_gap 0.5)
				(thermal_bridge_width 0.5)
				(island_removal_mode 0)
			)
			(polygon
				(pts
					(xy 171.323 -74.676) (xy 170.815 -74.676) (xy 170.815 -74.295) (xy 171.323 -74.295)
				)
			)
		)
		(zone
			(layer "B.Cu")
			(hatch none 0.5)
			(connect_pads
				(clearance 0)
			)
			(min_thickness 0.25)
			(keepout
				(tracks not_allowed)
				(vias allowed)
				(pads allowed)
				(copperpour not_allowed)
				(footprints allowed)
			)
			(placement
				(enabled no)
				(sheetname "")
			)
			(fill
				(thermal_gap 0.5)
				(thermal_bridge_width 0.5)
				(island_removal_mode 0)
			)
			(polygon
				(pts
					(xy 171.323 -74.295) (xy 170.815 -74.295) (xy 170.815 -74.676) (xy 171.323 -74.676)
				)
			)
		)
	)
	(footprint ""
		(layer "B.Cu")
		(at 409.067 -48.768)
		(property "Reference" "R1T6"
			(at 0 0 0)
			(layer "B.SilkS")
			(hide yes)
			(effects
				(font
					(size 1.27 1.27)
				)
				(justify mirror)
			)
		)
		(property "Value" ""
			(at 0 0 0)
			(layer "B.Fab")
			(effects
				(font
					(size 1.27 1.27)
				)
				(justify mirror)
			)
		)
		(duplicate_pad_numbers_are_jumpers no)
		(fp_poly
			(pts
				(xy 0.2794 -0.1016) (xy -0.2794 -0.1016) (xy -0.2794 0.9906) (xy 0.2794 0.9906)
			)
			(stroke
				(width 0)
				(type default)
			)
			(fill no)
			(layer "B.CrtYd")
		)
		(fp_line
			(start -0.2794 -0.1016)
			(end 0.2794 -0.1016)
			(stroke
				(width 0.1)
				(type default)
			)
			(layer "B.Fab")
		)
		(fp_line
			(start -0.2794 0.9906)
			(end -0.2794 -0.1016)
			(stroke
				(width 0.1)
				(type default)
			)
			(layer "B.Fab")
		)
		(fp_line
			(start 0.2794 -0.1016)
			(end 0.2794 0.9906)
			(stroke
				(width 0.1)
				(type default)
			)
			(layer "B.Fab")
		)
		(fp_line
			(start 0.2794 0.9906)
			(end -0.2794 0.9906)
			(stroke
				(width 0.1)
				(type default)
			)
			(layer "B.Fab")
		)
		(pad "1" smd rect
			(at 0 0 180)
			(size 0.508 0.508)
			(layers "B.Cu" "B.Mask" "B.Paste")
			(net "P3V3_STBY")
		)
		(pad "2" smd rect
			(at 0 0.889 180)
			(size 0.508 0.508)
			(layers "B.Cu" "B.Mask" "B.Paste")
			(net "FM_BOARD_REV_ID1")
		)
	)
	(footprint ""
		(layer "B.Cu")
		(at 480.1108 -57.1754 90)
		(property "Reference" "R8E30"
			(at 0 0 90)
			(layer "B.SilkS")
			(hide yes)
			(effects
				(font
					(size 1.27 1.27)
				)
				(justify mirror)
			)
		)
		(property "Value" "*"
			(at -0.064008 -4.108196 90)
			(unlocked yes)
			(layer "B.Fab")
			(hide yes)
			(effects
				(font
					(size 1.27 1.016)
					(thickness 0.1524)
				)
				(justify mirror)
			)
		)
		(property "Device Type" "2K15R2F-1-GP_SMD-RG1-2K15R2F-1A"
			(at -0.064008 -5.632196 90)
			(unlocked yes)
			(layer "B.Fab")
			(hide yes)
			(effects
				(font
					(size 1.27 1.016)
					(thickness 0.1524)
				)
				(justify mirror)
			)
		)
		(duplicate_pad_numbers_are_jumpers no)
		(fp_line
			(start 0.508 -0.9398)
			(end 0.508 0.9398)
			(stroke
				(width 0.1524)
				(type default)
			)
			(layer "B.SilkS")
		)
		(fp_line
			(start -0.508 -0.9398)
			(end 0.508 -0.9398)
			(stroke
				(width 0.1524)
				(type default)
			)
			(layer "B.SilkS")
		)
		(fp_rect
			(start 0.508 0.9398)
			(end -0.508 -0.9398)
			(stroke
				(width 0)
				(type default)
			)
			(fill no)
			(layer "B.CrtYd")
		)
		(fp_rect
			(start 0.508 0.9398)
			(end -0.508 -0.9398)
			(stroke
				(width 0)
				(type default)
			)
			(fill no)
			(layer "B.Fab")
		)
		(pad "1" smd custom
			(at 0 -0.4445 270)
			(size 0.1397 0.1397)
			(layers "B.Cu" "B.Mask" "B.Paste")
			(net "P3V3_STBY")
			(options
				(clearance outline)
				(anchor circle)
			)
			(primitives
				(gr_poly
					(pts
						(arc
							(start -0.1778 0.2794)
							(mid -0.249642 0.249642)
							(end -0.2794 0.1778)
						)
						(arc
							(start -0.2794 -0.1778)
							(mid -0.249642 -0.249642)
							(end -0.1778 -0.2794)
						)
						(arc
							(start 0.1778 -0.2794)
							(mid 0.249642 -0.249642)
							(end 0.2794 -0.1778)
						)
						(arc
							(start 0.2794 0.1778)
							(mid 0.249642 0.249642)
							(end 0.1778 0.2794)
						)
					)
					(width 0)
					(fill yes)
				)
			)
		)
		(pad "2" smd custom
			(at 0 0.4445 270)
			(size 0.1397 0.1397)
			(layers "B.Cu" "B.Mask" "B.Paste")
			(net "FM_ALL_WAKE_N")
			(options
				(clearance outline)
				(anchor circle)
			)
			(primitives
				(gr_poly
					(pts
						(arc
							(start -0.1778 0.2794)
							(mid -0.249642 0.249642)
							(end -0.2794 0.1778)
						)
						(arc
							(start -0.2794 -0.1778)
							(mid -0.249642 -0.249642)
							(end -0.1778 -0.2794)
						)
						(arc
							(start 0.1778 -0.2794)
							(mid 0.249642 -0.249642)
							(end 0.2794 -0.1778)
						)
						(arc
							(start 0.2794 0.1778)
							(mid 0.249642 0.249642)
							(end 0.1778 0.2794)
						)
					)
					(width 0)
					(fill yes)
				)
			)
		)
	)
	(footprint ""
		(layer "B.Cu")
		(at 53.80228 -165.01618 90)
		(property "Reference" "T1D11"
			(at 0 0 90)
			(layer "B.SilkS")
			(hide yes)
			(effects
				(font
					(size 1.27 1.27)
				)
				(justify mirror)
			)
		)
		(property "Value" "*"
			(at 3.4036 -4.46405 90)
			(unlocked yes)
			(layer "B.Fab")
			(hide yes)
			(effects
				(font
					(size 0.889 0.889)
					(thickness 0.1524)
				)
				(justify mirror)
			)
		)
		(property "Device Type" "TEST-PAD-12P-1-GP-U_DISCRET-GBA"
			(at 3.4036 -5.98805 90)
			(unlocked yes)
			(layer "B.Fab")
			(hide yes)
			(effects
				(font
					(size 0.889 0.889)
					(thickness 0.1524)
				)
				(justify mirror)
			)
		)
		(duplicate_pad_numbers_are_jumpers no)
		(fp_line
			(start 2.3876 -4.826)
			(end -2.3622 -4.826)
			(stroke
				(width 0.1524)
				(type default)
			)
			(layer "B.SilkS")
		)
		(fp_line
			(start -2.3622 -4.826)
			(end -2.3622 3.4798)
			(stroke
				(width 0.1524)
				(type default)
			)
			(layer "B.SilkS")
		)
		(fp_line
			(start 2.3876 3.4798)
			(end 2.3876 -4.826)
			(stroke
				(width 0.1524)
				(type default)
			)
			(layer "B.SilkS")
		)
		(fp_line
			(start -2.3622 3.4798)
			(end 2.3876 3.4798)
			(stroke
				(width 0.1524)
				(type default)
			)
			(layer "B.SilkS")
		)
		(fp_rect
			(start 2.6416 3.7338)
			(end -2.6162 -5.08)
			(stroke
				(width 0)
				(type default)
			)
			(fill no)
			(layer "B.CrtYd")
		)
		(fp_rect
			(start 2.6416 3.7338)
			(end -2.6162 -5.08)
			(stroke
				(width 0)
				(type default)
			)
			(fill no)
			(layer "B.Fab")
		)
		(pad "1" smd circle
			(at -0.496824 -1.301496 270)
			(size 0.6604 0.6604)
			(layers "B.Cu" "B.Mask" "B.Paste")
			(net "L14_85OHM_5INCH_DP")
		)
		(pad "2" smd circle
			(at 0.503936 -1.301496 270)
			(size 0.6604 0.6604)
			(layers "B.Cu" "B.Mask" "B.Paste")
			(net "L14_85OHM_5INCH_DN")
		)
		(pad "3" smd custom
			(at 0.00889 0.370078 270)
			(size 0.74295 0.74295)
			(layers "B.Cu" "B.Mask" "B.Paste")
			(net "GND")
			(options
				(clearance outline)
				(anchor circle)
			)
			(primitives
				(gr_poly
					(pts
						(xy -2.1209 -1.4859) (xy 2.1209 -1.4859) (xy 2.1209 1.4859) (xy 1.08585 1.4859) (xy 1.08585 0.4699)
						(xy -1.08585 0.4699) (xy -1.08585 1.4859) (xy -2.1209 1.4859)
					)
					(width 0)
					(fill yes)
				)
			)
		)
		(pad "4" thru_hole circle
			(at -1.266444 -3.851656 270)
			(size 1.4478 1.4478)
			(drill 1.0414)
			(layers "*.Cu" "*.Mask")
			(remove_unused_layers no)
			(net "GND")
			(clearance 0.1524)
			(thermal_gap 0.1524)
		)
		(pad "5" thru_hole circle
			(at 1.273556 -3.851656 270)
			(size 1.4478 1.4478)
			(drill 1.0414)
			(layers "*.Cu" "*.Mask")
			(remove_unused_layers no)
			(net "GND")
			(clearance 0.1524)
			(thermal_gap 0.1524)
		)
		(pad "6" thru_hole circle
			(at -1.266444 2.498344 270)
			(size 1.4478 1.4478)
			(drill 1.0414)
			(layers "*.Cu" "*.Mask")
			(remove_unused_layers no)
			(net "GND")
			(clearance 0.1524)
			(thermal_gap 0.1524)
		)
		(pad "7" thru_hole circle
			(at 1.273556 2.498344 270)
			(size 1.4478 1.4478)
			(drill 1.0414)
			(layers "*.Cu" "*.Mask")
			(remove_unused_layers no)
			(net "GND")
			(clearance 0.1524)
			(thermal_gap 0.1524)
		)
		(pad "8" thru_hole circle
			(at -1.27 -0.4572 270)
			(size 0.7112 0.7112)
			(drill 0.4064)
			(layers "*.Cu" "*.Mask")
			(remove_unused_layers no)
			(net "GND")
			(clearance 0.1016)
			(thermal_gap 0.1016)
		)
		(pad "9" thru_hole circle
			(at -1.27 0.762 270)
			(size 0.7112 0.7112)
			(drill 0.4064)
			(layers "*.Cu" "*.Mask")
			(remove_unused_layers no)
			(net "GND")
			(clearance 0.1016)
			(thermal_gap 0.1016)
		)
		(pad "10" thru_hole circle
			(at 0.0254 0.762 270)
			(size 0.7112 0.7112)
			(drill 0.4064)
			(layers "*.Cu" "*.Mask")
			(remove_unused_layers no)
			(net "GND")
			(clearance 0.1016)
			(thermal_gap 0.1016)
		)
		(pad "11" thru_hole circle
			(at 1.27 0.762 270)
			(size 0.7112 0.7112)
			(drill 0.4064)
			(layers "*.Cu" "*.Mask")
			(remove_unused_layers no)
			(net "GND")
			(clearance 0.1016)
			(thermal_gap 0.1016)
		)
		(pad "12" thru_hole circle
			(at 1.27 -0.4572 270)
			(size 0.7112 0.7112)
			(drill 0.4064)
			(layers "*.Cu" "*.Mask")
			(remove_unused_layers no)
			(net "GND")
			(clearance 0.1016)
			(thermal_gap 0.1016)
		)
	)
	(footprint ""
		(layer "B.Cu")
		(at 117.221 -77.216 -90)
		(property "Reference" "R7P11"
			(at 0 0 90)
			(layer "B.SilkS")
			(hide yes)
			(effects
				(font
					(size 1.27 1.27)
				)
				(justify mirror)
			)
		)
		(property "Value" ""
			(at 0 0 90)
			(layer "B.Fab")
			(effects
				(font
					(size 1.27 1.27)
				)
				(justify mirror)
			)
		)
		(duplicate_pad_numbers_are_jumpers no)
		(fp_poly
			(pts
				(xy 0.2794 -0.1016) (xy -0.2794 -0.1016) (xy -0.2794 0.9906) (xy 0.2794 0.9906)
			)
			(stroke
				(width 0)
				(type default)
			)
			(fill no)
			(layer "B.CrtYd")
		)
		(fp_line
			(start -0.2794 0.9906)
			(end -0.2794 -0.1016)
			(stroke
				(width 0.1)
				(type default)
			)
			(layer "B.Fab")
		)
		(fp_line
			(start 0.2794 0.9906)
			(end -0.2794 0.9906)
			(stroke
				(width 0.1)
				(type default)
			)
			(layer "B.Fab")
		)
		(fp_line
			(start -0.2794 -0.1016)
			(end 0.2794 -0.1016)
			(stroke
				(width 0.1)
				(type default)
			)
			(layer "B.Fab")
		)
		(fp_line
			(start 0.2794 -0.1016)
			(end 0.2794 0.9906)
			(stroke
				(width 0.1)
				(type default)
			)
			(layer "B.Fab")
		)
		(pad "1" smd rect
			(at 0 0 90)
			(size 0.508 0.508)
			(layers "B.Cu" "B.Mask" "B.Paste")
			(net "A_CPU1_UPI2_RBIAS")
		)
		(pad "2" smd rect
			(at 0 0.889 90)
			(size 0.508 0.508)
			(layers "B.Cu" "B.Mask" "B.Paste")
			(net "GND")
		)
		(zone
			(layer "B.Cu")
			(hatch none 0.5)
			(connect_pads
				(clearance 0)
			)
			(min_thickness 0.25)
			(keepout
				(tracks not_allowed)
				(vias allowed)
				(pads allowed)
				(copperpour not_allowed)
				(footprints allowed)
			)
			(placement
				(enabled no)
				(sheetname "")
			)
			(fill
				(thermal_gap 0.5)
				(thermal_bridge_width 0.5)
				(island_removal_mode 0)
			)
			(polygon
				(pts
					(xy 116.586 -76.962) (xy 116.586 -77.47) (xy 116.967 -77.47) (xy 116.967 -76.962)
				)
			)
		)
		(zone
			(layer "B.Cu")
			(hatch none 0.5)
			(connect_pads
				(clearance 0)
			)
			(min_thickness 0.25)
			(keepout
				(tracks allowed)
				(vias not_allowed)
				(pads allowed)
				(copperpour not_allowed)
				(footprints allowed)
			)
			(placement
				(enabled no)
				(sheetname "")
			)
			(fill
				(thermal_gap 0.5)
				(thermal_bridge_width 0.5)
				(island_removal_mode 0)
			)
			(polygon
				(pts
					(xy 116.967 -76.962) (xy 116.967 -77.47) (xy 116.586 -77.47) (xy 116.586 -76.962)
				)
			)
		)
	)
)
